# S9S_MB_2U (Grand Teton) — schematic netlist excerpt (pin names and nets, part order shuffled) for the footprints in the layout excerpt that follows; sources: Cadence DE-HDL packaged netlist, KiCad conversion of 03242023_DA0F0TMBIJ0_F0T_Motherboard_J_brd_V01_OCP.brd

U196  74LVC2G17GW  IC  pkg SOT363  page 151
  A0  = FM_GPU_PWR_EN_R
  GND  = GND
  A1  = GPU_FPGA_RST_R_N
  B1  = GPU_FPGA_RST_R1_BUF_N
  VCC  = P3V3_AUX
  B0  = FM_GPU_PWR_EN_R1

PC1867  Q_CAPP  560UF 6.3V 20% OSCON  pkg THLF  page 259 : A = P3V3_AUX ; B = GND

(kicad_pcb
	(version 20260206)
	(generator "pcbnew")
	(generator_version "10.0")
	(general
		(thickness 1.6)
		(legacy_teardrops no)
	)
	(paper "A4")
	(title_block
		(title "03242023_DA0F0TMBIJ0_F0T_Motherboard_J_brd_V01_OCP.brd")
		(comment 1 "Grand Teton / footprints 1598-1599 of 6105")
	)
	(layers
		(0 "F.Cu" signal "TOP")
		(4 "In1.Cu" signal "GND")
		(6 "In2.Cu" signal "IN1")
		(8 "In3.Cu" signal "GND1")
		(10 "In4.Cu" signal "IN2")
		(12 "In5.Cu" signal "GND2")
		(14 "In6.Cu" signal "IN3")
		(16 "In7.Cu" signal "GND3")
		(18 "In8.Cu" signal "VCC")
		(20 "In9.Cu" signal "VCC1")
		(22 "In10.Cu" signal "GND4")
		(24 "In11.Cu" signal "IN4")
		(26 "In12.Cu" signal "GND5")
		(28 "In13.Cu" signal "IN5")
		(30 "In14.Cu" signal "GND6")
		(32 "In15.Cu" signal "IN6")
		(34 "In16.Cu" signal "GND7")
		(2 "B.Cu" signal "BOTTOM")
		(9 "F.Adhes" user "F.Adhesive")
		(11 "B.Adhes" user "B.Adhesive")
		(13 "F.Paste" user "Package Geometry/Pastemask Top")
		(15 "B.Paste" user "Package Geometry/Pastemask Bottom")
		(5 "F.SilkS" user "Ref Des/Silkscreen Top")
		(7 "B.SilkS" user "Ref Des/Silkscreen Bottom")
		(1 "F.Mask" user "Board Geometry/Soldermask Top")
		(3 "B.Mask" user "Board Geometry/Soldermask Bottom")
		(17 "Dwgs.User" user "User.Drawings")
		(19 "Cmts.User" user "User.Comments")
		(21 "Eco1.User" user "User.Eco1")
		(23 "Eco2.User" user "User.Eco2")
		(25 "Edge.Cuts" user "Board Geometry/Outline")
		(27 "Margin" user)
		(31 "F.CrtYd" user "Package Geometry/Place Bound Top")
		(29 "B.CrtYd" user "Package Geometry/Place Bound Bottom")
		(35 "F.Fab" user "Ref Des/Assembly Top")
		(33 "B.Fab" user "Ref Des/Assembly Bottom")
	)
	(footprint ""
		(layer "F.Cu")
		(at 116.41328 -417.393628)
		(property "Reference" "U196"
			(at -2.4765 -2.74447 0)
			(unlocked yes)
			(layer "F.SilkS")
			(effects
				(font
					(size 0.7874 0.5842)
					(thickness 0.1524)
				)
				(justify left)
			)
		)
		(property "Value" ""
			(at 0 0 0)
			(layer "F.Fab")
			(effects
				(font
					(size 1.27 1.27)
				)
			)
		)
		(duplicate_pad_numbers_are_jumpers no)
		(fp_line
			(start -1.3462 -1.100074)
			(end -0.670052 -1.100074)
			(stroke
				(width 0.1524)
				(type default)
			)
			(layer "F.SilkS")
		)
		(fp_line
			(start -1.3462 1.100074)
			(end -1.3462 -1.100074)
			(stroke
				(width 0.1524)
				(type default)
			)
			(layer "F.SilkS")
		)
		(fp_line
			(start -0.670052 -1.100074)
			(end 0 -0.381)
			(stroke
				(width 0.1524)
				(type default)
			)
			(layer "F.SilkS")
		)
		(fp_line
			(start 0 -0.381)
			(end 0.670052 -1.100074)
			(stroke
				(width 0.1524)
				(type default)
			)
			(layer "F.SilkS")
		)
		(fp_line
			(start 0.670052 -1.100074)
			(end 1.3462 -1.100074)
			(stroke
				(width 0.1524)
				(type default)
			)
			(layer "F.SilkS")
		)
		(fp_line
			(start 1.3462 -1.100074)
			(end 1.3462 1.100074)
			(stroke
				(width 0.1524)
				(type default)
			)
			(layer "F.SilkS")
		)
		(fp_line
			(start 1.3462 1.100074)
			(end -1.3462 1.100074)
			(stroke
				(width 0.1524)
				(type default)
			)
			(layer "F.SilkS")
		)
		(fp_poly
			(pts
				(xy -0.990854 -1.28016) (xy -1.371854 -2.04216) (xy -0.609854 -2.04216)
			)
			(stroke
				(width 0)
				(type default)
			)
			(fill yes)
			(layer "F.SilkS")
		)
		(fp_line
			(start -1.100074 -0.8001)
			(end -0.670052 -0.8001)
			(stroke
				(width 0.1)
				(type default)
			)
			(layer "F.Fab")
		)
		(fp_line
			(start -1.100074 0.8001)
			(end -1.100074 -0.8001)
			(stroke
				(width 0.1)
				(type default)
			)
			(layer "F.Fab")
		)
		(fp_line
			(start -0.670052 -1.100074)
			(end 0.670052 -1.100074)
			(stroke
				(width 0.1)
				(type default)
			)
			(layer "F.Fab")
		)
		(fp_line
			(start -0.670052 -0.8001)
			(end -0.670052 -1.100074)
			(stroke
				(width 0.1)
				(type default)
			)
			(layer "F.Fab")
		)
		(fp_line
			(start -0.670052 0.8001)
			(end -1.100074 0.8001)
			(stroke
				(width 0.1)
				(type default)
			)
			(layer "F.Fab")
		)
		(fp_line
			(start -0.670052 0.8001)
			(end -0.670052 -0.8001)
			(stroke
				(width 0.1)
				(type default)
			)
			(layer "F.Fab")
		)
		(fp_line
			(start -0.670052 1.100074)
			(end -0.670052 0.8001)
			(stroke
				(width 0.1)
				(type default)
			)
			(layer "F.Fab")
		)
		(fp_line
			(start 0.670052 -1.100074)
			(end 0.670052 -0.8001)
			(stroke
				(width 0.1)
				(type default)
			)
			(layer "F.Fab")
		)
		(fp_line
			(start 0.670052 -0.8001)
			(end 0.670052 0.8001)
			(stroke
				(width 0.1)
				(type default)
			)
			(layer "F.Fab")
		)
		(fp_line
			(start 0.670052 -0.8001)
			(end 1.100074 -0.8001)
			(stroke
				(width 0.1)
				(type default)
			)
			(layer "F.Fab")
		)
		(fp_line
			(start 0.670052 0.8001)
			(end 0.670052 1.100074)
			(stroke
				(width 0.1)
				(type default)
			)
			(layer "F.Fab")
		)
		(fp_line
			(start 0.670052 1.100074)
			(end -0.670052 1.100074)
			(stroke
				(width 0.1)
				(type default)
			)
			(layer "F.Fab")
		)
		(fp_line
			(start 1.100074 -0.8001)
			(end 1.100074 0.8001)
			(stroke
				(width 0.1)
				(type default)
			)
			(layer "F.Fab")
		)
		(fp_line
			(start 1.100074 0.8001)
			(end 0.670052 0.8001)
			(stroke
				(width 0.1)
				(type default)
			)
			(layer "F.Fab")
		)
		(fp_poly
			(pts
				(xy -1.524 -0.649986) (xy -2.286 -1.030986) (xy -2.286 -0.268986)
			)
			(stroke
				(width 0)
				(type default)
			)
			(fill yes)
			(layer "F.Fab")
		)
		(pad "1" smd rect
			(at -0.94996 -0.649986 270)
			(size 0.4064 0.508)
			(layers "F.Cu" "F.Mask" "F.Paste")
			(net "FM_GPU_PWR_EN_R")
		)
		(pad "2" smd rect
			(at -0.94996 0 270)
			(size 0.4064 0.508)
			(layers "F.Cu" "F.Mask" "F.Paste")
			(net "GND")
		)
		(pad "3" smd rect
			(at -0.94996 0.649986 270)
			(size 0.4064 0.508)
			(layers "F.Cu" "F.Mask" "F.Paste")
			(net "GPU_FPGA_RST_R_N")
		)
		(pad "4" smd rect
			(at 0.94996 0.649986 270)
			(size 0.4064 0.508)
			(layers "F.Cu" "F.Mask" "F.Paste")
			(net "GPU_FPGA_RST_R1_BUF_N")
		)
		(pad "5" smd rect
			(at 0.94996 0 270)
			(size 0.4064 0.508)
			(layers "F.Cu" "F.Mask" "F.Paste")
			(net "P3V3_AUX")
		)
		(pad "6" smd rect
			(at 0.94996 -0.649986 270)
			(size 0.4064 0.508)
			(layers "F.Cu" "F.Mask" "F.Paste")
			(net "FM_GPU_PWR_EN_R1")
		)
	)
	(footprint ""
		(layer "F.Cu")
		(at 457.0349 -51.976528)
		(property "Reference" "PC1867"
			(at 0 0 0)
			(layer "F.SilkS")
			(hide yes)
			(effects
				(font
					(size 1.27 1.27)
				)
			)
		)
		(property "Value" ""
			(at 0 0 0)
			(layer "F.Fab")
			(effects
				(font
					(size 1.27 1.27)
				)
			)
		)
		(duplicate_pad_numbers_are_jumpers no)
		(fp_line
			(start -3.400044 1.249934)
			(end 3.400044 1.249934)
			(stroke
				(width 0.1524)
				(type default)
			)
			(layer "F.SilkS")
		)
		(fp_circle
			(center 0 1.249934)
			(end 3.400044 1.249934)
			(stroke
				(width 0.1524)
				(type default)
			)
			(fill no)
			(layer "F.SilkS")
		)
		(fp_poly
			(pts
				(arc
					(start 3.400044 1.249934)
					(mid 0 4.649978)
					(end -3.400044 1.249934)
				)
			)
			(stroke
				(width 0)
				(type default)
			)
			(fill yes)
			(layer "F.SilkS")
		)
		(fp_circle
			(center 0 1.249934)
			(end 3.400044 1.249934)
			(stroke
				(width 0.1)
				(type default)
			)
			(fill no)
			(layer "F.Fab")
		)
		(pad "1" thru_hole rect
			(at 0 0)
			(size 1.524 1.524)
			(drill 1.016)
			(layers "*.Cu" "*.Mask")
			(remove_unused_layers no)
			(net "P3V3_AUX")
			(clearance 0)
			(padstack
				(mode front_inner_back)
				(layer "Inner"
					(shape circle)
					(size 1.524 1.524)
					(clearance 0)
				)
				(layer "B.Cu"
					(shape rect)
					(size 1.524 1.524)
					(clearance 0)
				)
			)
		)
		(pad "2" thru_hole circle
			(at 0 2.500122)
			(size 1.524 1.524)
			(drill 1.016)
			(layers "*.Cu" "*.Mask")
			(remove_unused_layers no)
			(net "GND")
			(clearance 0)
		)
	)
)
